(kicad_pcb
	(version 20260206)
	(generator "pcbnew")
	(generator_version "10.0")
	(general
		(thickness 1.6)
		(legacy_teardrops no)
	)
	(paper "A4")
	(title_block
		(title "pdpb — Lightning_PDPB_BRD.brd")
		(comment 1 "Lightning (Wiwynn / Facebook NVMe JBOF) / footprints 1055-1060 of 1140")
	)
	(layers
		(0 "F.Cu" signal "TOP")
		(4 "In1.Cu" signal "L2GND")
		(6 "In2.Cu" signal "L3")
		(8 "In3.Cu" signal "L4VCC")
		(10 "In4.Cu" signal "L5VCC")
		(12 "In5.Cu" signal "L6")
		(14 "In6.Cu" signal "L7GND")
		(2 "B.Cu" signal "BOTTOM")
		(9 "F.Adhes" user "F.Adhesive")
		(11 "B.Adhes" user "B.Adhesive")
		(13 "F.Paste" user "Package Geometry/Pastemask Top")
		(15 "B.Paste" user "Package Geometry/Pastemask Bottom")
		(5 "F.SilkS" user "Ref Des/Silkscreen Top")
		(7 "B.SilkS" user "Ref Des/Silkscreen Bottom")
		(1 "F.Mask" user "Board Geometry/Soldermask Top")
		(3 "B.Mask" user "Board Geometry/Soldermask Bottom")
		(17 "Dwgs.User" user "User.Drawings")
		(19 "Cmts.User" user "User.Comments")
		(21 "Eco1.User" user "User.Eco1")
		(23 "Eco2.User" user "User.Eco2")
		(25 "Edge.Cuts" user "Board Geometry/Outline")
		(27 "Margin" user)
		(31 "F.CrtYd" user "Package Geometry/Place Bound Top")
		(29 "B.CrtYd" user "Package Geometry/Place Bound Bottom")
		(35 "F.Fab" user "Ref Des/Assembly Top")
		(33 "B.Fab" user "Ref Des/Assembly Bottom")
	)
	(footprint ""
		(layer "F.Cu")
		(at 25.7302 -471.6526)
		(property "Reference" "Q78"
			(at 0 0 0)
			(layer "F.SilkS")
			(hide yes)
			(effects
				(font
					(size 1.27 1.27)
				)
			)
		)
		(property "Value" "2N7002A-7-GP"
			(at 0.127 -8.9662 0)
			(unlocked yes)
			(layer "F.Fab")
			(hide yes)
			(effects
				(font
					(size 1.016 1.016)
					(thickness 0.1524)
				)
			)
		)
		(property "Device Type" "SOT23DGS2D4H48"
			(at 0.127 -10.4902 0)
			(unlocked yes)
			(layer "F.Fab")
			(hide yes)
			(effects
				(font
					(size 1.016 1.016)
					(thickness 0.1524)
				)
			)
		)
		(duplicate_pad_numbers_are_jumpers no)
		(fp_line
			(start -1.651 -1.778)
			(end -1.651 1.778)
			(stroke
				(width 0.1524)
				(type default)
			)
			(layer "F.SilkS")
		)
		(fp_line
			(start -1.651 1.778)
			(end 1.651 1.778)
			(stroke
				(width 0.1524)
				(type default)
			)
			(layer "F.SilkS")
		)
		(fp_line
			(start 1.651 -1.778)
			(end -1.651 -1.778)
			(stroke
				(width 0.1524)
				(type default)
			)
			(layer "F.SilkS")
		)
		(fp_line
			(start 1.651 1.778)
			(end 1.651 -1.778)
			(stroke
				(width 0.1524)
				(type default)
			)
			(layer "F.SilkS")
		)
		(fp_poly
			(pts
				(xy -1.778 1.8796) (xy -1.778 -1.8796) (xy 1.778 -1.8796) (xy 1.778 1.8796)
			)
			(stroke
				(width 0)
				(type default)
			)
			(fill no)
			(layer "F.CrtYd")
		)
		(fp_poly
			(pts
				(xy -1.778 1.8796) (xy -1.778 -1.8796) (xy 1.778 -1.8796) (xy 1.778 1.8796)
			)
			(stroke
				(width 0)
				(type default)
			)
			(fill no)
			(layer "F.Fab")
		)
		(pad "D" smd custom
			(at 0 -0.9525)
			(size 0.1905 0.1905)
			(layers "F.Cu" "F.Mask" "F.Paste")
			(net "SSD_ACT_DR10_MOS_N")
			(options
				(clearance outline)
				(anchor circle)
			)
			(primitives
				(gr_poly
					(pts
						(arc
							(start -0.1778 0.5715)
							(mid -0.321484 0.511984)
							(end -0.381 0.3683)
						)
						(arc
							(start -0.381 -0.3683)
							(mid -0.321484 -0.511984)
							(end -0.1778 -0.5715)
						)
						(arc
							(start 0.1778 -0.5715)
							(mid 0.321484 -0.511984)
							(end 0.381 -0.3683)
						)
						(arc
							(start 0.381 0.3683)
							(mid 0.321484 0.511984)
							(end 0.1778 0.5715)
						)
					)
					(width 0)
					(fill yes)
				)
			)
		)
		(pad "G" smd custom
			(at -0.98425 0.9525)
			(size 0.1905 0.1905)
			(layers "F.Cu" "F.Mask" "F.Paste")
			(net "ATTN_LED_DR10_AND_R")
			(options
				(clearance outline)
				(anchor circle)
			)
			(primitives
				(gr_poly
					(pts
						(arc
							(start -0.1778 0.5715)
							(mid -0.321484 0.511984)
							(end -0.381 0.3683)
						)
						(arc
							(start -0.381 -0.3683)
							(mid -0.321484 -0.511984)
							(end -0.1778 -0.5715)
						)
						(arc
							(start 0.1778 -0.5715)
							(mid 0.321484 -0.511984)
							(end 0.381 -0.3683)
						)
						(arc
							(start 0.381 0.3683)
							(mid 0.321484 0.511984)
							(end 0.1778 0.5715)
						)
					)
					(width 0)
					(fill yes)
				)
			)
		)
		(pad "S" smd custom
			(at 0.98425 0.9525)
			(size 0.1905 0.1905)
			(layers "F.Cu" "F.Mask" "F.Paste")
			(net "SSD_ACT_DR10_R")
			(options
				(clearance outline)
				(anchor circle)
			)
			(primitives
				(gr_poly
					(pts
						(arc
							(start -0.1778 0.5715)
							(mid -0.321484 0.511984)
							(end -0.381 0.3683)
						)
						(arc
							(start -0.381 -0.3683)
							(mid -0.321484 -0.511984)
							(end -0.1778 -0.5715)
						)
						(arc
							(start 0.1778 -0.5715)
							(mid 0.321484 -0.511984)
							(end 0.381 -0.3683)
						)
						(arc
							(start 0.381 0.3683)
							(mid 0.321484 0.511984)
							(end 0.1778 0.5715)
						)
					)
					(width 0)
					(fill yes)
				)
			)
		)
	)
	(footprint ""
		(layer "F.Cu")
		(at 24.892 -159.887158 90)
		(property "Reference" "Q94"
			(at 0 0 90)
			(layer "F.SilkS")
			(hide yes)
			(effects
				(font
					(size 1.27 1.27)
				)
			)
		)
		(property "Value" "2N7002A-7-GP"
			(at 0.127 -8.9662 90)
			(unlocked yes)
			(layer "F.Fab")
			(hide yes)
			(effects
				(font
					(size 1.016 1.016)
					(thickness 0.1524)
				)
			)
		)
		(property "Device Type" "SOT23DGS2D4H48"
			(at 0.127 -10.4902 90)
			(unlocked yes)
			(layer "F.Fab")
			(hide yes)
			(effects
				(font
					(size 1.016 1.016)
					(thickness 0.1524)
				)
			)
		)
		(duplicate_pad_numbers_are_jumpers no)
		(fp_line
			(start 1.651 -1.778)
			(end -1.651 -1.778)
			(stroke
				(width 0.1524)
				(type default)
			)
			(layer "F.SilkS")
		)
		(fp_line
			(start -1.651 -1.778)
			(end -1.651 1.778)
			(stroke
				(width 0.1524)
				(type default)
			)
			(layer "F.SilkS")
		)
		(fp_line
			(start 1.651 1.778)
			(end 1.651 -1.778)
			(stroke
				(width 0.1524)
				(type default)
			)
			(layer "F.SilkS")
		)
		(fp_line
			(start -1.651 1.778)
			(end 1.651 1.778)
			(stroke
				(width 0.1524)
				(type default)
			)
			(layer "F.SilkS")
		)
		(fp_poly
			(pts
				(xy -1.778 1.8796) (xy -1.778 -1.8796) (xy 1.778 -1.8796) (xy 1.778 1.8796)
			)
			(stroke
				(width 0)
				(type default)
			)
			(fill no)
			(layer "F.CrtYd")
		)
		(fp_poly
			(pts
				(xy -1.778 1.8796) (xy -1.778 -1.8796) (xy 1.778 -1.8796) (xy 1.778 1.8796)
			)
			(stroke
				(width 0)
				(type default)
			)
			(fill no)
			(layer "F.Fab")
		)
		(pad "D" smd custom
			(at 0 -0.9525 90)
			(size 0.1905 0.1905)
			(layers "F.Cu" "F.Mask" "F.Paste")
			(net "SSD13_CLK0_OE_MOS_N")
			(options
				(clearance outline)
				(anchor circle)
			)
			(primitives
				(gr_poly
					(pts
						(arc
							(start -0.1778 0.5715)
							(mid -0.321484 0.511984)
							(end -0.381 0.3683)
						)
						(arc
							(start -0.381 -0.3683)
							(mid -0.321484 -0.511984)
							(end -0.1778 -0.5715)
						)
						(arc
							(start 0.1778 -0.5715)
							(mid 0.321484 -0.511984)
							(end 0.381 -0.3683)
						)
						(arc
							(start 0.381 0.3683)
							(mid 0.321484 0.511984)
							(end 0.1778 0.5715)
						)
					)
					(width 0)
					(fill yes)
				)
			)
		)
		(pad "G" smd custom
			(at -0.98425 0.9525 90)
			(size 0.1905 0.1905)
			(layers "F.Cu" "F.Mask" "F.Paste")
			(net "SSD13_CLK0_OE_R_N")
			(options
				(clearance outline)
				(anchor circle)
			)
			(primitives
				(gr_poly
					(pts
						(arc
							(start -0.1778 0.5715)
							(mid -0.321484 0.511984)
							(end -0.381 0.3683)
						)
						(arc
							(start -0.381 -0.3683)
							(mid -0.321484 -0.511984)
							(end -0.1778 -0.5715)
						)
						(arc
							(start 0.1778 -0.5715)
							(mid 0.321484 -0.511984)
							(end 0.381 -0.3683)
						)
						(arc
							(start 0.381 0.3683)
							(mid 0.321484 0.511984)
							(end 0.1778 0.5715)
						)
					)
					(width 0)
					(fill yes)
				)
			)
		)
		(pad "S" smd custom
			(at 0.98425 0.9525 90)
			(size 0.1905 0.1905)
			(layers "F.Cu" "F.Mask" "F.Paste")
			(net "GND")
			(options
				(clearance outline)
				(anchor circle)
			)
			(primitives
				(gr_poly
					(pts
						(arc
							(start -0.1778 0.5715)
							(mid -0.321484 0.511984)
							(end -0.381 0.3683)
						)
						(arc
							(start -0.381 -0.3683)
							(mid -0.321484 -0.511984)
							(end -0.1778 -0.5715)
						)
						(arc
							(start 0.1778 -0.5715)
							(mid 0.321484 -0.511984)
							(end 0.381 -0.3683)
						)
						(arc
							(start 0.381 0.3683)
							(mid 0.321484 0.511984)
							(end 0.1778 0.5715)
						)
					)
					(width 0)
					(fill yes)
				)
			)
		)
	)
	(footprint ""
		(layer "F.Cu")
		(at 222.758 -431.292)
		(property "Reference" "PC1274"
			(at 0 0 0)
			(layer "F.SilkS")
			(hide yes)
			(effects
				(font
					(size 1.27 1.27)
				)
			)
		)
		(property "Value" "SCD1U50V3KX-GP"
			(at 0 -2.8194 0)
			(unlocked yes)
			(layer "F.Fab")
			(hide yes)
			(effects
				(font
					(size 1.016 1.016)
					(thickness 0.1524)
				)
			)
		)
		(property "Device Type" "C603H36"
			(at 0 -4.3434 0)
			(unlocked yes)
			(layer "F.Fab")
			(hide yes)
			(effects
				(font
					(size 1.016 1.016)
					(thickness 0.1524)
				)
			)
		)
		(duplicate_pad_numbers_are_jumpers no)
		(fp_line
			(start 0.508 0)
			(end -0.508 0)
			(stroke
				(width 0.2032)
				(type default)
			)
			(layer "F.SilkS")
		)
		(fp_rect
			(start -0.5842 1.3335)
			(end 0.5842 -1.3335)
			(stroke
				(width 0)
				(type default)
			)
			(fill no)
			(layer "F.CrtYd")
		)
		(fp_rect
			(start -0.5842 1.3335)
			(end 0.5842 -1.3335)
			(stroke
				(width 0)
				(type default)
			)
			(fill no)
			(layer "F.Fab")
		)
		(pad "1" smd custom
			(at 0 -0.762)
			(size 0.2159 0.2159)
			(layers "F.Cu" "F.Mask" "F.Paste")
			(net "P3V3_SW")
			(options
				(clearance outline)
				(anchor circle)
			)
			(primitives
				(gr_poly
					(pts
						(arc
							(start -0.3302 -0.4318)
							(mid -0.402042 -0.402042)
							(end -0.4318 -0.3302)
						)
						(arc
							(start -0.4318 0.3302)
							(mid -0.402042 0.402042)
							(end -0.3302 0.4318)
						)
						(arc
							(start 0.3302 0.4318)
							(mid 0.402042 0.402042)
							(end 0.4318 0.3302)
						)
						(arc
							(start 0.4318 -0.3302)
							(mid 0.402042 -0.402042)
							(end 0.3302 -0.4318)
						)
					)
					(width 0)
					(fill yes)
				)
			)
		)
		(pad "2" smd custom
			(at 0 0.762)
			(size 0.2159 0.2159)
			(layers "F.Cu" "F.Mask" "F.Paste")
			(net "P3V3_VBST_RR")
			(options
				(clearance outline)
				(anchor circle)
			)
			(primitives
				(gr_poly
					(pts
						(arc
							(start -0.3302 -0.4318)
							(mid -0.402042 -0.402042)
							(end -0.4318 -0.3302)
						)
						(arc
							(start -0.4318 0.3302)
							(mid -0.402042 0.402042)
							(end -0.3302 0.4318)
						)
						(arc
							(start 0.3302 0.4318)
							(mid 0.402042 0.402042)
							(end 0.4318 0.3302)
						)
						(arc
							(start 0.4318 -0.3302)
							(mid 0.402042 -0.402042)
							(end 0.3302 -0.4318)
						)
					)
					(width 0)
					(fill yes)
				)
			)
		)
	)
	(footprint ""
		(layer "F.Cu")
		(at 42.926 -141.30782 90)
		(property "Reference" "R9835"
			(at 0 0 90)
			(layer "F.SilkS")
			(hide yes)
			(effects
				(font
					(size 1.27 1.27)
				)
			)
		)
		(property "Value" "0R2J-2-GP"
			(at 0.064008 -3.993896 90)
			(unlocked yes)
			(layer "F.Fab")
			(hide yes)
			(effects
				(font
					(size 1.016 1.016)
					(thickness 0.1524)
				)
			)
		)
		(property "Device Type" "R402H16"
			(at 0.064008 -5.517896 90)
			(unlocked yes)
			(layer "F.Fab")
			(hide yes)
			(effects
				(font
					(size 1.016 1.016)
					(thickness 0.1524)
				)
			)
		)
		(duplicate_pad_numbers_are_jumpers no)
		(fp_line
			(start 0.508 -0.9398)
			(end -0.508 -0.9398)
			(stroke
				(width 0.1524)
				(type default)
			)
			(layer "F.SilkS")
		)
		(fp_line
			(start -0.508 -0.9398)
			(end -0.508 0.9398)
			(stroke
				(width 0.1524)
				(type default)
			)
			(layer "F.SilkS")
		)
		(fp_rect
			(start -0.508 0.9398)
			(end 0.508 -0.9398)
			(stroke
				(width 0)
				(type default)
			)
			(fill no)
			(layer "F.CrtYd")
		)
		(fp_rect
			(start -0.508 0.9398)
			(end 0.508 -0.9398)
			(stroke
				(width 0)
				(type default)
			)
			(fill no)
			(layer "F.Fab")
		)
		(pad "1" smd custom
			(at 0 -0.4445 90)
			(size 0.1397 0.1397)
			(layers "F.Cu" "F.Mask" "F.Paste")
			(net "ATTN_LED_DR8_AND")
			(options
				(clearance outline)
				(anchor circle)
			)
			(primitives
				(gr_poly
					(pts
						(arc
							(start -0.1778 -0.2794)
							(mid -0.249642 -0.249642)
							(end -0.2794 -0.1778)
						)
						(arc
							(start -0.2794 0.1778)
							(mid -0.249642 0.249642)
							(end -0.1778 0.2794)
						)
						(arc
							(start 0.1778 0.2794)
							(mid 0.249642 0.249642)
							(end 0.2794 0.1778)
						)
						(arc
							(start 0.2794 -0.1778)
							(mid 0.249642 -0.249642)
							(end 0.1778 -0.2794)
						)
					)
					(width 0)
					(fill yes)
				)
			)
		)
		(pad "2" smd custom
			(at 0 0.4445 90)
			(size 0.1397 0.1397)
			(layers "F.Cu" "F.Mask" "F.Paste")
			(net "ATTN_LED_DR8_AND_R")
			(options
				(clearance outline)
				(anchor circle)
			)
			(primitives
				(gr_poly
					(pts
						(arc
							(start -0.1778 -0.2794)
							(mid -0.249642 -0.249642)
							(end -0.2794 -0.1778)
						)
						(arc
							(start -0.2794 0.1778)
							(mid -0.249642 0.249642)
							(end -0.1778 0.2794)
						)
						(arc
							(start 0.1778 0.2794)
							(mid 0.249642 0.249642)
							(end 0.2794 0.1778)
						)
						(arc
							(start 0.2794 -0.1778)
							(mid 0.249642 -0.249642)
							(end 0.1778 -0.2794)
						)
					)
					(width 0)
					(fill yes)
				)
			)
		)
	)
	(footprint ""
		(layer "F.Cu")
		(at 70.739 -437.388 -90)
		(property "Reference" "R367"
			(at 0 0 270)
			(layer "F.SilkS")
			(hide yes)
			(effects
				(font
					(size 1.27 1.27)
				)
			)
		)
		(property "Value" "4K7R2J-2-GP"
			(at 0.064008 -3.993896 270)
			(unlocked yes)
			(layer "F.Fab")
			(hide yes)
			(effects
				(font
					(size 1.016 1.016)
					(thickness 0.1524)
				)
			)
		)
		(property "Device Type" "R402H16"
			(at 0.064008 -5.517896 270)
			(unlocked yes)
			(layer "F.Fab")
			(hide yes)
			(effects
				(font
					(size 1.016 1.016)
					(thickness 0.1524)
				)
			)
		)
		(duplicate_pad_numbers_are_jumpers no)
		(fp_line
			(start -0.508 -0.9398)
			(end -0.508 0.9398)
			(stroke
				(width 0.1524)
				(type default)
			)
			(layer "F.SilkS")
		)
		(fp_line
			(start 0.508 -0.9398)
			(end -0.508 -0.9398)
			(stroke
				(width 0.1524)
				(type default)
			)
			(layer "F.SilkS")
		)
		(fp_rect
			(start -0.508 0.9398)
			(end 0.508 -0.9398)
			(stroke
				(width 0)
				(type default)
			)
			(fill no)
			(layer "F.CrtYd")
		)
		(fp_rect
			(start -0.508 0.9398)
			(end 0.508 -0.9398)
			(stroke
				(width 0)
				(type default)
			)
			(fill no)
			(layer "F.Fab")
		)
		(pad "1" smd custom
			(at 0 -0.4445 270)
			(size 0.1397 0.1397)
			(layers "F.Cu" "F.Mask" "F.Paste")
			(net "P3V3")
			(options
				(clearance outline)
				(anchor circle)
			)
			(primitives
				(gr_poly
					(pts
						(arc
							(start -0.1778 -0.2794)
							(mid -0.249642 -0.249642)
							(end -0.2794 -0.1778)
						)
						(arc
							(start -0.2794 0.1778)
							(mid -0.249642 0.249642)
							(end -0.1778 0.2794)
						)
						(arc
							(start 0.1778 0.2794)
							(mid 0.249642 0.249642)
							(end 0.2794 0.1778)
						)
						(arc
							(start 0.2794 -0.1778)
							(mid 0.249642 -0.249642)
							(end 0.1778 -0.2794)
						)
					)
					(width 0)
					(fill yes)
				)
			)
		)
		(pad "2" smd custom
			(at 0 0.4445 270)
			(size 0.1397 0.1397)
			(layers "F.Cu" "F.Mask" "F.Paste")
			(net "I2C_B_SCL")
			(options
				(clearance outline)
				(anchor circle)
			)
			(primitives
				(gr_poly
					(pts
						(arc
							(start -0.1778 -0.2794)
							(mid -0.249642 -0.249642)
							(end -0.2794 -0.1778)
						)
						(arc
							(start -0.2794 0.1778)
							(mid -0.249642 0.249642)
							(end -0.1778 0.2794)
						)
						(arc
							(start 0.1778 0.2794)
							(mid 0.249642 0.249642)
							(end 0.2794 0.1778)
						)
						(arc
							(start 0.2794 -0.1778)
							(mid 0.249642 -0.249642)
							(end 0.1778 -0.2794)
						)
					)
					(width 0)
					(fill yes)
				)
			)
		)
	)
	(footprint ""
		(layer "F.Cu")
		(at 85.471 -429.514 90)
		(property "Reference" "PR9009"
			(at 0 0 90)
			(layer "F.SilkS")
			(hide yes)
			(effects
				(font
					(size 1.27 1.27)
				)
			)
		)
		(property "Value" "4K7R2F-GP"
			(at 0.064008 -3.993896 90)
			(unlocked yes)
			(layer "F.Fab")
			(hide yes)
			(effects
				(font
					(size 1.016 1.016)
					(thickness 0.1524)
				)
			)
		)
		(property "Device Type" "R402H16"
			(at 0.064008 -5.517896 90)
			(unlocked yes)
			(layer "F.Fab")
			(hide yes)
			(effects
				(font
					(size 1.016 1.016)
					(thickness 0.1524)
				)
			)
		)
		(duplicate_pad_numbers_are_jumpers no)
		(fp_line
			(start 0.508 -0.9398)
			(end -0.508 -0.9398)
			(stroke
				(width 0.1524)
				(type default)
			)
			(layer "F.SilkS")
		)
		(fp_line
			(start -0.508 -0.9398)
			(end -0.508 0.9398)
			(stroke
				(width 0.1524)
				(type default)
			)
			(layer "F.SilkS")
		)
		(fp_rect
			(start -0.508 0.9398)
			(end 0.508 -0.9398)
			(stroke
				(width 0)
				(type default)
			)
			(fill no)
			(layer "F.CrtYd")
		)
		(fp_rect
			(start -0.508 0.9398)
			(end 0.508 -0.9398)
			(stroke
				(width 0)
				(type default)
			)
			(fill no)
			(layer "F.Fab")
		)
		(pad "1" smd custom
			(at 0 -0.4445 90)
			(size 0.1397 0.1397)
			(layers "F.Cu" "F.Mask" "F.Paste")
			(net "VDD_DIFF_1")
			(options
				(clearance outline)
				(anchor circle)
			)
			(primitives
				(gr_poly
					(pts
						(arc
							(start -0.1778 -0.2794)
							(mid -0.249642 -0.249642)
							(end -0.2794 -0.1778)
						)
						(arc
							(start -0.2794 0.1778)
							(mid -0.249642 0.249642)
							(end -0.1778 0.2794)
						)
						(arc
							(start 0.1778 0.2794)
							(mid 0.249642 0.249642)
							(end 0.2794 0.1778)
						)
						(arc
							(start 0.2794 -0.1778)
							(mid 0.249642 -0.249642)
							(end 0.1778 -0.2794)
						)
					)
					(width 0)
					(fill yes)
				)
			)
		)
		(pad "2" smd custom
			(at 0 0.4445 90)
			(size 0.1397 0.1397)
			(layers "F.Cu" "F.Mask" "F.Paste")
			(net "CLK_BUF_EU1_SMB_A0_TRI")
			(options
				(clearance outline)
				(anchor circle)
			)
			(primitives
				(gr_poly
					(pts
						(arc
							(start -0.1778 -0.2794)
							(mid -0.249642 -0.249642)
							(end -0.2794 -0.1778)
						)
						(arc
							(start -0.2794 0.1778)
							(mid -0.249642 0.249642)
							(end -0.1778 0.2794)
						)
						(arc
							(start 0.1778 0.2794)
							(mid 0.249642 0.249642)
							(end 0.2794 0.1778)
						)
						(arc
							(start 0.2794 -0.1778)
							(mid 0.249642 -0.249642)
							(end 0.1778 -0.2794)
						)
					)
					(width 0)
					(fill yes)
				)
			)
		)
	)
)
